(kicad_pcb
	(version 20260206)
	(generator "pcbnew")
	(generator_version "10.0")
	(general
		(thickness 1.6)
		(legacy_teardrops no)
	)
	(paper "A4")
	(title_block
		(title "04192023_DAF0TMB3IC0_F0TG_MB_C_brd_V02_OCP.brd")
		(comment 1 "Grand Teton / footprints 6069-6075 of 8354")
	)
	(layers
		(0 "F.Cu" signal "TOP")
		(4 "In1.Cu" signal "GND")
		(6 "In2.Cu" signal "IN1")
		(8 "In3.Cu" signal "GND1")
		(10 "In4.Cu" signal "IN2")
		(12 "In5.Cu" signal "GND2")
		(14 "In6.Cu" signal "IN3")
		(16 "In7.Cu" signal "GND3")
		(18 "In8.Cu" signal "VCC")
		(20 "In9.Cu" signal "VCC1")
		(22 "In10.Cu" signal "GND4")
		(24 "In11.Cu" signal "IN4")
		(26 "In12.Cu" signal "GND5")
		(28 "In13.Cu" signal "IN5")
		(30 "In14.Cu" signal "GND6")
		(32 "In15.Cu" signal "IN6")
		(34 "In16.Cu" signal "GND7")
		(2 "B.Cu" signal "BOTTOM")
		(9 "F.Adhes" user "F.Adhesive")
		(11 "B.Adhes" user "B.Adhesive")
		(13 "F.Paste" user "Package Geometry/Pastemask Top")
		(15 "B.Paste" user "Package Geometry/Pastemask Bottom")
		(5 "F.SilkS" user "Ref Des/Silkscreen Top")
		(7 "B.SilkS" user "Ref Des/Silkscreen Bottom")
		(1 "F.Mask" user "Board Geometry/Soldermask Top")
		(3 "B.Mask" user "Board Geometry/Soldermask Bottom")
		(17 "Dwgs.User" user "User.Drawings")
		(19 "Cmts.User" user "User.Comments")
		(21 "Eco1.User" user "User.Eco1")
		(23 "Eco2.User" user "User.Eco2")
		(25 "Edge.Cuts" user "Board Geometry/Outline")
		(27 "Margin" user)
		(31 "F.CrtYd" user "Package Geometry/Place Bound Top")
		(29 "B.CrtYd" user "Package Geometry/Place Bound Bottom")
		(35 "F.Fab" user "Ref Des/Assembly Top")
		(33 "B.Fab" user "Ref Des/Assembly Bottom")
	)
	(footprint ""
		(layer "B.Cu")
		(at 33.02 -361.569 -90)
		(property "Reference" "PR533"
			(at 0 0 90)
			(layer "B.SilkS")
			(hide yes)
			(effects
				(font
					(size 1.27 1.27)
				)
				(justify mirror)
			)
		)
		(property "Value" ""
			(at 0 0 90)
			(layer "B.Fab")
			(effects
				(font
					(size 1.27 1.27)
				)
				(justify mirror)
			)
		)
		(duplicate_pad_numbers_are_jumpers no)
		(fp_line
			(start -0.7874 0.4064)
			(end 0.7874 0.4064)
			(stroke
				(width 0.1524)
				(type default)
			)
			(layer "B.SilkS")
		)
		(fp_line
			(start 0.7874 0.4064)
			(end 0.7874 -0.4064)
			(stroke
				(width 0.1524)
				(type default)
			)
			(layer "B.SilkS")
		)
		(fp_line
			(start -0.7874 -0.4064)
			(end -0.7874 0.4064)
			(stroke
				(width 0.1524)
				(type default)
			)
			(layer "B.SilkS")
		)
		(fp_line
			(start 0.7874 -0.4064)
			(end -0.7874 -0.4064)
			(stroke
				(width 0.1524)
				(type default)
			)
			(layer "B.SilkS")
		)
		(fp_line
			(start -0.67945 0.3048)
			(end -0.120396 0.3048)
			(stroke
				(width 0.1)
				(type default)
			)
			(layer "B.Fab")
		)
		(fp_line
			(start -0.120396 0.3048)
			(end -0.120396 0.2794)
			(stroke
				(width 0.1)
				(type default)
			)
			(layer "B.Fab")
		)
		(fp_line
			(start 0.12065 0.3048)
			(end 0.67945 0.3048)
			(stroke
				(width 0.1)
				(type default)
			)
			(layer "B.Fab")
		)
		(fp_line
			(start 0.67945 0.3048)
			(end 0.67945 -0.305054)
			(stroke
				(width 0.1)
				(type default)
			)
			(layer "B.Fab")
		)
		(fp_line
			(start -0.120396 0.2794)
			(end 0.12065 0.2794)
			(stroke
				(width 0.1)
				(type default)
			)
			(layer "B.Fab")
		)
		(fp_line
			(start 0.12065 0.2794)
			(end 0.12065 0.3048)
			(stroke
				(width 0.1)
				(type default)
			)
			(layer "B.Fab")
		)
		(fp_line
			(start -0.12065 -0.2794)
			(end -0.12065 -0.3048)
			(stroke
				(width 0.1)
				(type default)
			)
			(layer "B.Fab")
		)
		(fp_line
			(start 0.12065 -0.2794)
			(end -0.12065 -0.2794)
			(stroke
				(width 0.1)
				(type default)
			)
			(layer "B.Fab")
		)
		(fp_line
			(start -0.67945 -0.3048)
			(end -0.67945 0.3048)
			(stroke
				(width 0.1)
				(type default)
			)
			(layer "B.Fab")
		)
		(fp_line
			(start -0.12065 -0.3048)
			(end -0.67945 -0.3048)
			(stroke
				(width 0.1)
				(type default)
			)
			(layer "B.Fab")
		)
		(fp_line
			(start 0.12065 -0.305054)
			(end 0.12065 -0.2794)
			(stroke
				(width 0.1)
				(type default)
			)
			(layer "B.Fab")
		)
		(fp_line
			(start 0.67945 -0.305054)
			(end 0.12065 -0.305054)
			(stroke
				(width 0.1)
				(type default)
			)
			(layer "B.Fab")
		)
		(pad "1" smd circle
			(at 0.40005 0 90)
			(size 0 0)
			(layers "B.Cu" "B.Mask" "B.Paste")
			(net "NC_PVDDCR_CPU1_P1_IMON7")
		)
		(pad "2" smd circle
			(at -0.40005 0 90)
			(size 0 0)
			(layers "B.Cu" "B.Mask" "B.Paste")
			(net "GND")
		)
	)
	(footprint ""
		(layer "B.Cu")
		(at 135.858504 -31.874206 -90)
		(property "Reference" "C6052"
			(at 0 0 90)
			(layer "B.SilkS")
			(hide yes)
			(effects
				(font
					(size 1.27 1.27)
				)
				(justify mirror)
			)
		)
		(property "Value" ""
			(at 0 0 90)
			(layer "B.Fab")
			(effects
				(font
					(size 1.27 1.27)
				)
				(justify mirror)
			)
		)
		(duplicate_pad_numbers_are_jumpers no)
		(fp_line
			(start -0.7874 0.4064)
			(end 0.7874 0.4064)
			(stroke
				(width 0.1524)
				(type default)
			)
			(layer "B.SilkS")
		)
		(fp_line
			(start 0.7874 0.4064)
			(end 0.7874 -0.4064)
			(stroke
				(width 0.1524)
				(type default)
			)
			(layer "B.SilkS")
		)
		(fp_line
			(start -0.7874 -0.4064)
			(end -0.7874 0.4064)
			(stroke
				(width 0.1524)
				(type default)
			)
			(layer "B.SilkS")
		)
		(fp_line
			(start 0.7874 -0.4064)
			(end -0.7874 -0.4064)
			(stroke
				(width 0.1524)
				(type default)
			)
			(layer "B.SilkS")
		)
		(fp_line
			(start -0.67945 0.3048)
			(end -0.120396 0.3048)
			(stroke
				(width 0.1)
				(type default)
			)
			(layer "B.Fab")
		)
		(fp_line
			(start -0.120396 0.3048)
			(end -0.120396 0.2794)
			(stroke
				(width 0.1)
				(type default)
			)
			(layer "B.Fab")
		)
		(fp_line
			(start 0.12065 0.3048)
			(end 0.67945 0.3048)
			(stroke
				(width 0.1)
				(type default)
			)
			(layer "B.Fab")
		)
		(fp_line
			(start 0.67945 0.3048)
			(end 0.67945 -0.305054)
			(stroke
				(width 0.1)
				(type default)
			)
			(layer "B.Fab")
		)
		(fp_line
			(start -0.120396 0.2794)
			(end 0.12065 0.2794)
			(stroke
				(width 0.1)
				(type default)
			)
			(layer "B.Fab")
		)
		(fp_line
			(start 0.12065 0.2794)
			(end 0.12065 0.3048)
			(stroke
				(width 0.1)
				(type default)
			)
			(layer "B.Fab")
		)
		(fp_line
			(start -0.12065 -0.2794)
			(end -0.12065 -0.3048)
			(stroke
				(width 0.1)
				(type default)
			)
			(layer "B.Fab")
		)
		(fp_line
			(start 0.12065 -0.2794)
			(end -0.12065 -0.2794)
			(stroke
				(width 0.1)
				(type default)
			)
			(layer "B.Fab")
		)
		(fp_line
			(start -0.67945 -0.3048)
			(end -0.67945 0.3048)
			(stroke
				(width 0.1)
				(type default)
			)
			(layer "B.Fab")
		)
		(fp_line
			(start -0.12065 -0.3048)
			(end -0.67945 -0.3048)
			(stroke
				(width 0.1)
				(type default)
			)
			(layer "B.Fab")
		)
		(fp_line
			(start 0.12065 -0.305054)
			(end 0.12065 -0.2794)
			(stroke
				(width 0.1)
				(type default)
			)
			(layer "B.Fab")
		)
		(fp_line
			(start 0.67945 -0.305054)
			(end 0.12065 -0.305054)
			(stroke
				(width 0.1)
				(type default)
			)
			(layer "B.Fab")
		)
		(pad "1" smd circle
			(at 0.40005 0 90)
			(size 0 0)
			(layers "B.Cu" "B.Mask" "B.Paste")
			(net "P3V3_AUX")
		)
		(pad "2" smd circle
			(at -0.40005 0 90)
			(size 0 0)
			(layers "B.Cu" "B.Mask" "B.Paste")
			(net "GND")
		)
	)
	(footprint ""
		(layer "B.Cu")
		(at 89.506298 -386.766562 90)
		(property "Reference" "C217"
			(at 0 0 90)
			(layer "B.SilkS")
			(hide yes)
			(effects
				(font
					(size 1.27 1.27)
				)
				(justify mirror)
			)
		)
		(property "Value" ""
			(at 0 0 90)
			(layer "B.Fab")
			(effects
				(font
					(size 1.27 1.27)
				)
				(justify mirror)
			)
		)
		(duplicate_pad_numbers_are_jumpers no)
		(fp_line
			(start 0.299974 -0.150114)
			(end -0.299974 -0.150114)
			(stroke
				(width 0.1)
				(type default)
			)
			(layer "B.Fab")
		)
		(fp_line
			(start -0.299974 -0.150114)
			(end -0.299974 0.150114)
			(stroke
				(width 0.1)
				(type default)
			)
			(layer "B.Fab")
		)
		(fp_line
			(start 0.299974 0.150114)
			(end 0.299974 -0.150114)
			(stroke
				(width 0.1)
				(type default)
			)
			(layer "B.Fab")
		)
		(fp_line
			(start -0.299974 0.150114)
			(end 0.299974 0.150114)
			(stroke
				(width 0.1)
				(type default)
			)
			(layer "B.Fab")
		)
		(pad "1" smd rect
			(at 0.2667 0 270)
			(size 0.3048 0.381)
			(layers "B.Cu" "B.Mask" "B.Paste")
			(net "P1V8_CPU1_RT1_1A")
		)
		(pad "2" smd rect
			(at -0.2667 0 270)
			(size 0.3048 0.381)
			(layers "B.Cu" "B.Mask" "B.Paste")
			(net "GND")
		)
	)
	(footprint ""
		(layer "B.Cu")
		(at 381.278384 -395.148562 90)
		(property "Reference" "C999"
			(at 0 0 90)
			(layer "B.SilkS")
			(hide yes)
			(effects
				(font
					(size 1.27 1.27)
				)
				(justify mirror)
			)
		)
		(property "Value" ""
			(at 0 0 90)
			(layer "B.Fab")
			(effects
				(font
					(size 1.27 1.27)
				)
				(justify mirror)
			)
		)
		(duplicate_pad_numbers_are_jumpers no)
		(fp_line
			(start 0.299974 -0.150114)
			(end -0.299974 -0.150114)
			(stroke
				(width 0.1)
				(type default)
			)
			(layer "B.Fab")
		)
		(fp_line
			(start -0.299974 -0.150114)
			(end -0.299974 0.150114)
			(stroke
				(width 0.1)
				(type default)
			)
			(layer "B.Fab")
		)
		(fp_line
			(start 0.299974 0.150114)
			(end 0.299974 -0.150114)
			(stroke
				(width 0.1)
				(type default)
			)
			(layer "B.Fab")
		)
		(fp_line
			(start -0.299974 0.150114)
			(end 0.299974 0.150114)
			(stroke
				(width 0.1)
				(type default)
			)
			(layer "B.Fab")
		)
		(pad "1" smd rect
			(at 0.2667 0 270)
			(size 0.3048 0.381)
			(layers "B.Cu" "B.Mask" "B.Paste")
			(net "P1V8_CPU0_RT3_1A_1D")
		)
		(pad "2" smd rect
			(at -0.2667 0 270)
			(size 0.3048 0.381)
			(layers "B.Cu" "B.Mask" "B.Paste")
			(net "GND")
		)
	)
	(footprint ""
		(layer "B.Cu")
		(at 139.36472 -35.304222 -90)
		(property "Reference" "C6045"
			(at 0 0 90)
			(layer "B.SilkS")
			(hide yes)
			(effects
				(font
					(size 1.27 1.27)
				)
				(justify mirror)
			)
		)
		(property "Value" ""
			(at 0 0 90)
			(layer "B.Fab")
			(effects
				(font
					(size 1.27 1.27)
				)
				(justify mirror)
			)
		)
		(duplicate_pad_numbers_are_jumpers no)
		(fp_line
			(start -0.7874 0.4064)
			(end 0.7874 0.4064)
			(stroke
				(width 0.1524)
				(type default)
			)
			(layer "B.SilkS")
		)
		(fp_line
			(start 0.7874 0.4064)
			(end 0.7874 -0.4064)
			(stroke
				(width 0.1524)
				(type default)
			)
			(layer "B.SilkS")
		)
		(fp_line
			(start -0.7874 -0.4064)
			(end -0.7874 0.4064)
			(stroke
				(width 0.1524)
				(type default)
			)
			(layer "B.SilkS")
		)
		(fp_line
			(start 0.7874 -0.4064)
			(end -0.7874 -0.4064)
			(stroke
				(width 0.1524)
				(type default)
			)
			(layer "B.SilkS")
		)
		(fp_line
			(start -0.67945 0.3048)
			(end -0.120396 0.3048)
			(stroke
				(width 0.1)
				(type default)
			)
			(layer "B.Fab")
		)
		(fp_line
			(start -0.120396 0.3048)
			(end -0.120396 0.2794)
			(stroke
				(width 0.1)
				(type default)
			)
			(layer "B.Fab")
		)
		(fp_line
			(start 0.12065 0.3048)
			(end 0.67945 0.3048)
			(stroke
				(width 0.1)
				(type default)
			)
			(layer "B.Fab")
		)
		(fp_line
			(start 0.67945 0.3048)
			(end 0.67945 -0.305054)
			(stroke
				(width 0.1)
				(type default)
			)
			(layer "B.Fab")
		)
		(fp_line
			(start -0.120396 0.2794)
			(end 0.12065 0.2794)
			(stroke
				(width 0.1)
				(type default)
			)
			(layer "B.Fab")
		)
		(fp_line
			(start 0.12065 0.2794)
			(end 0.12065 0.3048)
			(stroke
				(width 0.1)
				(type default)
			)
			(layer "B.Fab")
		)
		(fp_line
			(start -0.12065 -0.2794)
			(end -0.12065 -0.3048)
			(stroke
				(width 0.1)
				(type default)
			)
			(layer "B.Fab")
		)
		(fp_line
			(start 0.12065 -0.2794)
			(end -0.12065 -0.2794)
			(stroke
				(width 0.1)
				(type default)
			)
			(layer "B.Fab")
		)
		(fp_line
			(start -0.67945 -0.3048)
			(end -0.67945 0.3048)
			(stroke
				(width 0.1)
				(type default)
			)
			(layer "B.Fab")
		)
		(fp_line
			(start -0.12065 -0.3048)
			(end -0.67945 -0.3048)
			(stroke
				(width 0.1)
				(type default)
			)
			(layer "B.Fab")
		)
		(fp_line
			(start 0.12065 -0.305054)
			(end 0.12065 -0.2794)
			(stroke
				(width 0.1)
				(type default)
			)
			(layer "B.Fab")
		)
		(fp_line
			(start 0.67945 -0.305054)
			(end 0.12065 -0.305054)
			(stroke
				(width 0.1)
				(type default)
			)
			(layer "B.Fab")
		)
		(pad "1" smd circle
			(at 0.40005 0 90)
			(size 0 0)
			(layers "B.Cu" "B.Mask" "B.Paste")
			(net "P3V3_AUX_CPU0_USB_AVDD33")
		)
		(pad "2" smd circle
			(at -0.40005 0 90)
			(size 0 0)
			(layers "B.Cu" "B.Mask" "B.Paste")
			(net "GND")
		)
	)
	(footprint ""
		(layer "B.Cu")
		(at 444.166752 -380.027434 90)
		(property "Reference" "PC6568"
			(at -6.293104 2.238248 0)
			(unlocked yes)
			(layer "B.SilkS")
			(effects
				(font
					(size 0.7874 0.5842)
					(thickness 0.1524)
				)
				(justify left mirror)
			)
		)
		(property "Value" ""
			(at 0 0 90)
			(layer "B.Fab")
			(effects
				(font
					(size 1.27 1.27)
				)
				(justify mirror)
			)
		)
		(duplicate_pad_numbers_are_jumpers no)
		(fp_line
			(start 4.84378 -2.150618)
			(end 4.53898 -2.150618)
			(stroke
				(width 0.1524)
				(type default)
			)
			(layer "B.SilkS")
		)
		(fp_line
			(start 4.84378 -2.150618)
			(end 4.842256 2.163064)
			(stroke
				(width 0.1524)
				(type default)
			)
			(layer "B.SilkS")
		)
		(fp_line
			(start 4.69138 -2.150618)
			(end 4.692396 2.161032)
			(stroke
				(width 0.1524)
				(type default)
			)
			(layer "B.SilkS")
		)
		(fp_line
			(start 4.53898 -2.150618)
			(end 4.539742 2.152142)
			(stroke
				(width 0.1524)
				(type default)
			)
			(layer "B.SilkS")
		)
		(fp_line
			(start 4.53898 -2.15011)
			(end -4.53898 -2.15011)
			(stroke
				(width 0.1524)
				(type default)
			)
			(layer "B.SilkS")
		)
		(fp_line
			(start -4.53898 -2.15011)
			(end -4.53898 2.15011)
			(stroke
				(width 0.1524)
				(type default)
			)
			(layer "B.SilkS")
		)
		(fp_line
			(start 4.53898 2.15011)
			(end 4.53898 -2.15011)
			(stroke
				(width 0.1524)
				(type default)
			)
			(layer "B.SilkS")
		)
		(fp_line
			(start -4.53898 2.15011)
			(end 4.53898 2.15011)
			(stroke
				(width 0.1524)
				(type default)
			)
			(layer "B.SilkS")
		)
		(fp_line
			(start 4.83108 2.150364)
			(end 4.447794 2.149348)
			(stroke
				(width 0.1524)
				(type default)
			)
			(layer "B.SilkS")
		)
		(fp_line
			(start 3.64998 -2.15011)
			(end -3.64998 -2.15011)
			(stroke
				(width 0.1)
				(type default)
			)
			(layer "B.Fab")
		)
		(fp_line
			(start -3.64998 -2.15011)
			(end -3.64998 2.15011)
			(stroke
				(width 0.1)
				(type default)
			)
			(layer "B.Fab")
		)
		(fp_line
			(start 3.64998 2.15011)
			(end 3.64998 -2.15011)
			(stroke
				(width 0.1)
				(type default)
			)
			(layer "B.Fab")
		)
		(fp_line
			(start -3.64998 2.15011)
			(end 3.64998 2.15011)
			(stroke
				(width 0.1)
				(type default)
			)
			(layer "B.Fab")
		)
		(fp_text user "+"
			(at 5.993638 -2.411222 90)
			(unlocked yes)
			(layer "B.SilkS")
			(effects
				(font
					(size 1.905 1.4224)
					(thickness 0.1524)
				)
				(justify left mirror)
			)
		)
		(fp_text user "-"
			(at -4.313174 -0.094488 90)
			(unlocked yes)
			(layer "B.SilkS")
			(effects
				(font
					(size 1.905 1.4224)
					(thickness 0.1524)
				)
				(justify left mirror)
			)
		)
		(fp_text user "+"
			(at 6.214872 -0.337058 90)
			(unlocked yes)
			(layer "B.Fab")
			(effects
				(font
					(size 1.905 1.4224)
					(thickness 0.1524)
				)
				(justify left mirror)
			)
		)
		(fp_text user "-"
			(at -4.313174 -0.094488 90)
			(unlocked yes)
			(layer "B.Fab")
			(effects
				(font
					(size 1.905 1.4224)
					(thickness 0.1524)
				)
				(justify left mirror)
			)
		)
		(pad "1" smd rect
			(at 3.199892 0 270)
			(size 2.413 2.8194)
			(layers "B.Cu" "B.Mask" "B.Paste")
			(net "P0V9_CPU0_RT_2D")
		)
		(pad "2" smd rect
			(at -3.199892 0 270)
			(size 2.413 2.8194)
			(layers "B.Cu" "B.Mask" "B.Paste")
			(net "GND")
		)
	)
	(footprint ""
		(layer "B.Cu")
		(at 350.596454 -264.35431)
		(property "Reference" "C2162"
			(at 0 0 0)
			(layer "B.SilkS")
			(hide yes)
			(effects
				(font
					(size 1.27 1.27)
				)
				(justify mirror)
			)
		)
		(property "Value" ""
			(at 0 0 0)
			(layer "B.Fab")
			(effects
				(font
					(size 1.27 1.27)
				)
				(justify mirror)
			)
		)
		(duplicate_pad_numbers_are_jumpers no)
		(fp_line
			(start -0.7874 -0.4064)
			(end -0.7874 0.4064)
			(stroke
				(width 0.1524)
				(type default)
			)
			(layer "B.SilkS")
		)
		(fp_line
			(start -0.7874 0.4064)
			(end 0.7874 0.4064)
			(stroke
				(width 0.1524)
				(type default)
			)
			(layer "B.SilkS")
		)
		(fp_line
			(start 0.7874 -0.4064)
			(end -0.7874 -0.4064)
			(stroke
				(width 0.1524)
				(type default)
			)
			(layer "B.SilkS")
		)
		(fp_line
			(start 0.7874 0.4064)
			(end 0.7874 -0.4064)
			(stroke
				(width 0.1524)
				(type default)
			)
			(layer "B.SilkS")
		)
		(fp_line
			(start -0.67945 -0.3048)
			(end -0.67945 0.3048)
			(stroke
				(width 0.1)
				(type default)
			)
			(layer "B.Fab")
		)
		(fp_line
			(start -0.67945 0.3048)
			(end -0.120396 0.3048)
			(stroke
				(width 0.1)
				(type default)
			)
			(layer "B.Fab")
		)
		(fp_line
			(start -0.12065 -0.3048)
			(end -0.67945 -0.3048)
			(stroke
				(width 0.1)
				(type default)
			)
			(layer "B.Fab")
		)
		(fp_line
			(start -0.12065 -0.2794)
			(end -0.12065 -0.3048)
			(stroke
				(width 0.1)
				(type default)
			)
			(layer "B.Fab")
		)
		(fp_line
			(start -0.120396 0.2794)
			(end 0.12065 0.2794)
			(stroke
				(width 0.1)
				(type default)
			)
			(layer "B.Fab")
		)
		(fp_line
			(start -0.120396 0.3048)
			(end -0.120396 0.2794)
			(stroke
				(width 0.1)
				(type default)
			)
			(layer "B.Fab")
		)
		(fp_line
			(start 0.12065 -0.305054)
			(end 0.12065 -0.2794)
			(stroke
				(width 0.1)
				(type default)
			)
			(layer "B.Fab")
		)
		(fp_line
			(start 0.12065 -0.2794)
			(end -0.12065 -0.2794)
			(stroke
				(width 0.1)
				(type default)
			)
			(layer "B.Fab")
		)
		(fp_line
			(start 0.12065 0.2794)
			(end 0.12065 0.3048)
			(stroke
				(width 0.1)
				(type default)
			)
			(layer "B.Fab")
		)
		(fp_line
			(start 0.12065 0.3048)
			(end 0.67945 0.3048)
			(stroke
				(width 0.1)
				(type default)
			)
			(layer "B.Fab")
		)
		(fp_line
			(start 0.67945 -0.305054)
			(end 0.12065 -0.305054)
			(stroke
				(width 0.1)
				(type default)
			)
			(layer "B.Fab")
		)
		(fp_line
			(start 0.67945 0.3048)
			(end 0.67945 -0.305054)
			(stroke
				(width 0.1)
				(type default)
			)
			(layer "B.Fab")
		)
		(pad "1" smd circle
			(at 0.40005 0 180)
			(size 0 0)
			(layers "B.Cu" "B.Mask" "B.Paste")
			(net "PVDD11_S3_P0")
		)
		(pad "2" smd circle
			(at -0.40005 0 180)
			(size 0 0)
			(layers "B.Cu" "B.Mask" "B.Paste")
			(net "GND")
		)
	)
)
